(kicad_pcb
	(version 20260206)
	(generator "pcbnew")
	(generator_version "10.0")
	(general
		(thickness 1.6)
		(legacy_teardrops no)
	)
	(paper "A4")
	(title_block
		(title "03242023_DA0F0TMBIJ0_F0T_Motherboard_J_brd_V01_OCP.brd")
		(comment 1 "Grand Teton / footprints 1453-1458 of 6105")
	)
	(layers
		(0 "F.Cu" signal "TOP")
		(4 "In1.Cu" signal "GND")
		(6 "In2.Cu" signal "IN1")
		(8 "In3.Cu" signal "GND1")
		(10 "In4.Cu" signal "IN2")
		(12 "In5.Cu" signal "GND2")
		(14 "In6.Cu" signal "IN3")
		(16 "In7.Cu" signal "GND3")
		(18 "In8.Cu" signal "VCC")
		(20 "In9.Cu" signal "VCC1")
		(22 "In10.Cu" signal "GND4")
		(24 "In11.Cu" signal "IN4")
		(26 "In12.Cu" signal "GND5")
		(28 "In13.Cu" signal "IN5")
		(30 "In14.Cu" signal "GND6")
		(32 "In15.Cu" signal "IN6")
		(34 "In16.Cu" signal "GND7")
		(2 "B.Cu" signal "BOTTOM")
		(9 "F.Adhes" user "F.Adhesive")
		(11 "B.Adhes" user "B.Adhesive")
		(13 "F.Paste" user "Package Geometry/Pastemask Top")
		(15 "B.Paste" user "Package Geometry/Pastemask Bottom")
		(5 "F.SilkS" user "Ref Des/Silkscreen Top")
		(7 "B.SilkS" user "Ref Des/Silkscreen Bottom")
		(1 "F.Mask" user "Board Geometry/Soldermask Top")
		(3 "B.Mask" user "Board Geometry/Soldermask Bottom")
		(17 "Dwgs.User" user "User.Drawings")
		(19 "Cmts.User" user "User.Comments")
		(21 "Eco1.User" user "User.Eco1")
		(23 "Eco2.User" user "User.Eco2")
		(25 "Edge.Cuts" user "Board Geometry/Outline")
		(27 "Margin" user)
		(31 "F.CrtYd" user "Package Geometry/Place Bound Top")
		(29 "B.CrtYd" user "Package Geometry/Place Bound Bottom")
		(35 "F.Fab" user "Ref Des/Assembly Top")
		(33 "B.Fab" user "Ref Des/Assembly Bottom")
	)
	(footprint ""
		(layer "F.Cu")
		(at 414.869122 -367.231676)
		(property "Reference" "PR354"
			(at 0 0 0)
			(layer "F.SilkS")
			(hide yes)
			(effects
				(font
					(size 1.27 1.27)
				)
			)
		)
		(property "Value" ""
			(at 0 0 0)
			(layer "F.Fab")
			(effects
				(font
					(size 1.27 1.27)
				)
			)
		)
		(duplicate_pad_numbers_are_jumpers no)
		(fp_line
			(start -0.7874 -0.4064)
			(end 0.7874 -0.4064)
			(stroke
				(width 0.1524)
				(type default)
			)
			(layer "F.SilkS")
		)
		(fp_line
			(start -0.7874 0.4064)
			(end -0.7874 -0.4064)
			(stroke
				(width 0.1524)
				(type default)
			)
			(layer "F.SilkS")
		)
		(fp_line
			(start 0.7874 -0.4064)
			(end 0.7874 0.4064)
			(stroke
				(width 0.1524)
				(type default)
			)
			(layer "F.SilkS")
		)
		(fp_line
			(start 0.7874 0.4064)
			(end -0.7874 0.4064)
			(stroke
				(width 0.1524)
				(type default)
			)
			(layer "F.SilkS")
		)
		(fp_line
			(start -0.67945 -0.305054)
			(end -0.12065 -0.305054)
			(stroke
				(width 0.1)
				(type default)
			)
			(layer "F.Fab")
		)
		(fp_line
			(start -0.67945 0.3048)
			(end -0.67945 -0.305054)
			(stroke
				(width 0.1)
				(type default)
			)
			(layer "F.Fab")
		)
		(fp_line
			(start -0.12065 -0.305054)
			(end -0.12065 -0.2794)
			(stroke
				(width 0.1)
				(type default)
			)
			(layer "F.Fab")
		)
		(fp_line
			(start -0.12065 -0.2794)
			(end 0.12065 -0.2794)
			(stroke
				(width 0.1)
				(type default)
			)
			(layer "F.Fab")
		)
		(fp_line
			(start -0.12065 0.2794)
			(end -0.12065 0.3048)
			(stroke
				(width 0.1)
				(type default)
			)
			(layer "F.Fab")
		)
		(fp_line
			(start -0.12065 0.3048)
			(end -0.67945 0.3048)
			(stroke
				(width 0.1)
				(type default)
			)
			(layer "F.Fab")
		)
		(fp_line
			(start 0.120396 0.2794)
			(end -0.12065 0.2794)
			(stroke
				(width 0.1)
				(type default)
			)
			(layer "F.Fab")
		)
		(fp_line
			(start 0.120396 0.3048)
			(end 0.120396 0.2794)
			(stroke
				(width 0.1)
				(type default)
			)
			(layer "F.Fab")
		)
		(fp_line
			(start 0.12065 -0.3048)
			(end 0.67945 -0.3048)
			(stroke
				(width 0.1)
				(type default)
			)
			(layer "F.Fab")
		)
		(fp_line
			(start 0.12065 -0.2794)
			(end 0.12065 -0.3048)
			(stroke
				(width 0.1)
				(type default)
			)
			(layer "F.Fab")
		)
		(fp_line
			(start 0.67945 -0.3048)
			(end 0.67945 0.3048)
			(stroke
				(width 0.1)
				(type default)
			)
			(layer "F.Fab")
		)
		(fp_line
			(start 0.67945 0.3048)
			(end 0.120396 0.3048)
			(stroke
				(width 0.1)
				(type default)
			)
			(layer "F.Fab")
		)
		(pad "1" smd circle
			(at -0.40005 0)
			(size 0 0)
			(layers "F.Cu" "F.Mask" "F.Paste")
			(net "PVCCFA_EHV_FIVRA_CPU0_LSET1")
		)
		(pad "2" smd circle
			(at 0.40005 0)
			(size 0 0)
			(layers "F.Cu" "F.Mask" "F.Paste")
			(net "GND")
		)
	)
	(footprint ""
		(layer "F.Cu")
		(at 157.00121 -70.26402 -90)
		(property "Reference" "R2311"
			(at 0 0 270)
			(layer "F.SilkS")
			(hide yes)
			(effects
				(font
					(size 1.27 1.27)
				)
			)
		)
		(property "Value" ""
			(at 0 0 270)
			(layer "F.Fab")
			(effects
				(font
					(size 1.27 1.27)
				)
			)
		)
		(duplicate_pad_numbers_are_jumpers no)
		(fp_line
			(start -0.7874 0.4064)
			(end -0.7874 -0.4064)
			(stroke
				(width 0.1524)
				(type default)
			)
			(layer "F.SilkS")
		)
		(fp_line
			(start 0.7874 0.4064)
			(end -0.7874 0.4064)
			(stroke
				(width 0.1524)
				(type default)
			)
			(layer "F.SilkS")
		)
		(fp_line
			(start -0.7874 -0.4064)
			(end 0.7874 -0.4064)
			(stroke
				(width 0.1524)
				(type default)
			)
			(layer "F.SilkS")
		)
		(fp_line
			(start 0.7874 -0.4064)
			(end 0.7874 0.4064)
			(stroke
				(width 0.1524)
				(type default)
			)
			(layer "F.SilkS")
		)
		(fp_line
			(start -0.67945 0.3048)
			(end -0.67945 -0.305054)
			(stroke
				(width 0.1)
				(type default)
			)
			(layer "F.Fab")
		)
		(fp_line
			(start -0.12065 0.3048)
			(end -0.67945 0.3048)
			(stroke
				(width 0.1)
				(type default)
			)
			(layer "F.Fab")
		)
		(fp_line
			(start 0.120396 0.3048)
			(end 0.120396 0.2794)
			(stroke
				(width 0.1)
				(type default)
			)
			(layer "F.Fab")
		)
		(fp_line
			(start 0.67945 0.3048)
			(end 0.120396 0.3048)
			(stroke
				(width 0.1)
				(type default)
			)
			(layer "F.Fab")
		)
		(fp_line
			(start -0.12065 0.2794)
			(end -0.12065 0.3048)
			(stroke
				(width 0.1)
				(type default)
			)
			(layer "F.Fab")
		)
		(fp_line
			(start 0.120396 0.2794)
			(end -0.12065 0.2794)
			(stroke
				(width 0.1)
				(type default)
			)
			(layer "F.Fab")
		)
		(fp_line
			(start -0.12065 -0.2794)
			(end 0.12065 -0.2794)
			(stroke
				(width 0.1)
				(type default)
			)
			(layer "F.Fab")
		)
		(fp_line
			(start 0.12065 -0.2794)
			(end 0.12065 -0.3048)
			(stroke
				(width 0.1)
				(type default)
			)
			(layer "F.Fab")
		)
		(fp_line
			(start 0.12065 -0.3048)
			(end 0.67945 -0.3048)
			(stroke
				(width 0.1)
				(type default)
			)
			(layer "F.Fab")
		)
		(fp_line
			(start 0.67945 -0.3048)
			(end 0.67945 0.3048)
			(stroke
				(width 0.1)
				(type default)
			)
			(layer "F.Fab")
		)
		(fp_line
			(start -0.67945 -0.305054)
			(end -0.12065 -0.305054)
			(stroke
				(width 0.1)
				(type default)
			)
			(layer "F.Fab")
		)
		(fp_line
			(start -0.12065 -0.305054)
			(end -0.12065 -0.2794)
			(stroke
				(width 0.1)
				(type default)
			)
			(layer "F.Fab")
		)
		(pad "1" smd circle
			(at -0.40005 0 270)
			(size 0 0)
			(layers "F.Cu" "F.Mask" "F.Paste")
			(net "PCA9543_S3M_ADDR0")
		)
		(pad "2" smd circle
			(at 0.40005 0 270)
			(size 0 0)
			(layers "F.Cu" "F.Mask" "F.Paste")
			(net "GND")
		)
	)
	(footprint ""
		(layer "F.Cu")
		(at 125.65888 -92.674948 90)
		(property "Reference" "R238"
			(at 0 0 90)
			(layer "F.SilkS")
			(hide yes)
			(effects
				(font
					(size 1.27 1.27)
				)
			)
		)
		(property "Value" ""
			(at 0 0 90)
			(layer "F.Fab")
			(effects
				(font
					(size 1.27 1.27)
				)
			)
		)
		(duplicate_pad_numbers_are_jumpers no)
		(fp_line
			(start 0.7874 -0.4064)
			(end 0.7874 0.4064)
			(stroke
				(width 0.1524)
				(type default)
			)
			(layer "F.SilkS")
		)
		(fp_line
			(start -0.7874 -0.4064)
			(end 0.7874 -0.4064)
			(stroke
				(width 0.1524)
				(type default)
			)
			(layer "F.SilkS")
		)
		(fp_line
			(start 0.7874 0.4064)
			(end -0.7874 0.4064)
			(stroke
				(width 0.1524)
				(type default)
			)
			(layer "F.SilkS")
		)
		(fp_line
			(start -0.7874 0.4064)
			(end -0.7874 -0.4064)
			(stroke
				(width 0.1524)
				(type default)
			)
			(layer "F.SilkS")
		)
		(fp_line
			(start -0.12065 -0.305054)
			(end -0.12065 -0.2794)
			(stroke
				(width 0.1)
				(type default)
			)
			(layer "F.Fab")
		)
		(fp_line
			(start -0.67945 -0.305054)
			(end -0.12065 -0.305054)
			(stroke
				(width 0.1)
				(type default)
			)
			(layer "F.Fab")
		)
		(fp_line
			(start 0.67945 -0.3048)
			(end 0.67945 0.3048)
			(stroke
				(width 0.1)
				(type default)
			)
			(layer "F.Fab")
		)
		(fp_line
			(start 0.12065 -0.3048)
			(end 0.67945 -0.3048)
			(stroke
				(width 0.1)
				(type default)
			)
			(layer "F.Fab")
		)
		(fp_line
			(start 0.12065 -0.2794)
			(end 0.12065 -0.3048)
			(stroke
				(width 0.1)
				(type default)
			)
			(layer "F.Fab")
		)
		(fp_line
			(start -0.12065 -0.2794)
			(end 0.12065 -0.2794)
			(stroke
				(width 0.1)
				(type default)
			)
			(layer "F.Fab")
		)
		(fp_line
			(start 0.120396 0.2794)
			(end -0.12065 0.2794)
			(stroke
				(width 0.1)
				(type default)
			)
			(layer "F.Fab")
		)
		(fp_line
			(start -0.12065 0.2794)
			(end -0.12065 0.3048)
			(stroke
				(width 0.1)
				(type default)
			)
			(layer "F.Fab")
		)
		(fp_line
			(start 0.67945 0.3048)
			(end 0.120396 0.3048)
			(stroke
				(width 0.1)
				(type default)
			)
			(layer "F.Fab")
		)
		(fp_line
			(start 0.120396 0.3048)
			(end 0.120396 0.2794)
			(stroke
				(width 0.1)
				(type default)
			)
			(layer "F.Fab")
		)
		(fp_line
			(start -0.12065 0.3048)
			(end -0.67945 0.3048)
			(stroke
				(width 0.1)
				(type default)
			)
			(layer "F.Fab")
		)
		(fp_line
			(start -0.67945 0.3048)
			(end -0.67945 -0.305054)
			(stroke
				(width 0.1)
				(type default)
			)
			(layer "F.Fab")
		)
		(pad "1" smd circle
			(at -0.40005 0 90)
			(size 0 0)
			(layers "F.Cu" "F.Mask" "F.Paste")
			(net "H_CPU1_THERMTRIP_LVC1_R_N")
		)
		(pad "2" smd circle
			(at 0.40005 0 90)
			(size 0 0)
			(layers "F.Cu" "F.Mask" "F.Paste")
			(net "H_CPU1_THERMTRIP_VT_R_N")
		)
	)
	(footprint ""
		(layer "F.Cu")
		(at 202.59802 -128.516888 180)
		(property "Reference" "U158"
			(at 1.68402 -2.72161 0)
			(unlocked yes)
			(layer "F.SilkS")
			(effects
				(font
					(size 0.7874 0.5842)
					(thickness 0.1524)
				)
				(justify left)
			)
		)
		(property "Value" ""
			(at 0 0 180)
			(layer "F.Fab")
			(effects
				(font
					(size 1.27 1.27)
				)
			)
		)
		(duplicate_pad_numbers_are_jumpers no)
		(fp_line
			(start 1.603248 1.500124)
			(end -1.603248 1.500124)
			(stroke
				(width 0.1524)
				(type default)
			)
			(layer "F.SilkS")
		)
		(fp_line
			(start 1.603248 -1.500124)
			(end 1.603248 1.500124)
			(stroke
				(width 0.1524)
				(type default)
			)
			(layer "F.SilkS")
		)
		(fp_line
			(start -1.603248 1.500124)
			(end -1.603248 -1.500124)
			(stroke
				(width 0.1524)
				(type default)
			)
			(layer "F.SilkS")
		)
		(fp_line
			(start -1.603248 -1.500124)
			(end 1.603248 -1.500124)
			(stroke
				(width 0.1524)
				(type default)
			)
			(layer "F.SilkS")
		)
		(fp_line
			(start 1.249934 0.219964)
			(end 1.249934 -0.219964)
			(stroke
				(width 0.1)
				(type default)
			)
			(layer "F.Fab")
		)
		(fp_line
			(start 1.249934 -0.219964)
			(end 0.700024 -0.219964)
			(stroke
				(width 0.1)
				(type default)
			)
			(layer "F.Fab")
		)
		(fp_line
			(start 0.700024 1.500124)
			(end 0.700024 0.219964)
			(stroke
				(width 0.1)
				(type default)
			)
			(layer "F.Fab")
		)
		(fp_line
			(start 0.700024 0.219964)
			(end 1.249934 0.219964)
			(stroke
				(width 0.1)
				(type default)
			)
			(layer "F.Fab")
		)
		(fp_line
			(start 0.700024 -0.219964)
			(end 0.700024 -1.500124)
			(stroke
				(width 0.1)
				(type default)
			)
			(layer "F.Fab")
		)
		(fp_line
			(start 0.700024 -1.500124)
			(end -0.700024 -1.500124)
			(stroke
				(width 0.1)
				(type default)
			)
			(layer "F.Fab")
		)
		(fp_line
			(start -0.6985 0.729996)
			(end -1.249934 0.729996)
			(stroke
				(width 0.1)
				(type default)
			)
			(layer "F.Fab")
		)
		(fp_line
			(start -0.6985 -0.729996)
			(end -0.6985 0.729996)
			(stroke
				(width 0.1)
				(type default)
			)
			(layer "F.Fab")
		)
		(fp_line
			(start -0.700024 1.500124)
			(end 0.700024 1.500124)
			(stroke
				(width 0.1)
				(type default)
			)
			(layer "F.Fab")
		)
		(fp_line
			(start -0.700024 1.169924)
			(end -0.700024 1.500124)
			(stroke
				(width 0.1)
				(type default)
			)
			(layer "F.Fab")
		)
		(fp_line
			(start -0.700024 -1.169924)
			(end -1.249934 -1.169924)
			(stroke
				(width 0.1)
				(type default)
			)
			(layer "F.Fab")
		)
		(fp_line
			(start -0.700024 -1.500124)
			(end -0.700024 -1.169924)
			(stroke
				(width 0.1)
				(type default)
			)
			(layer "F.Fab")
		)
		(fp_line
			(start -1.249934 1.169924)
			(end -0.700024 1.169924)
			(stroke
				(width 0.1)
				(type default)
			)
			(layer "F.Fab")
		)
		(fp_line
			(start -1.249934 0.729996)
			(end -1.249934 1.169924)
			(stroke
				(width 0.1)
				(type default)
			)
			(layer "F.Fab")
		)
		(fp_line
			(start -1.249934 -0.729996)
			(end -0.6985 -0.729996)
			(stroke
				(width 0.1)
				(type default)
			)
			(layer "F.Fab")
		)
		(fp_line
			(start -1.249934 -1.169924)
			(end -1.249934 -0.729996)
			(stroke
				(width 0.1)
				(type default)
			)
			(layer "F.Fab")
		)
		(fp_rect
			(start -0.700024 -1.500124)
			(end 0.700024 1.500124)
			(stroke
				(width 0)
				(type default)
			)
			(fill no)
			(layer "F.Fab")
		)
		(pad "D" smd rect
			(at 0.999998 0 90)
			(size 0.8128 0.9144)
			(layers "F.Cu" "F.Mask" "F.Paste")
			(net "FM_P12V_HSC_EN_N")
		)
		(pad "G" smd rect
			(at -0.999998 -0.94996 90)
			(size 0.8128 0.9144)
			(layers "F.Cu" "F.Mask" "F.Paste")
			(net "FM_P12V_HSC_EN_R")
		)
		(pad "S" smd rect
			(at -0.999998 0.94996 90)
			(size 0.8128 0.9144)
			(layers "F.Cu" "F.Mask" "F.Paste")
			(net "GND")
		)
	)
	(footprint ""
		(layer "F.Cu")
		(at 358.648 -402.844)
		(property "Reference" "Q152"
			(at 0.23876 1.764792 0)
			(unlocked yes)
			(layer "F.SilkS")
			(effects
				(font
					(size 0.7874 0.5842)
					(thickness 0.1524)
				)
				(justify left)
			)
		)
		(property "Value" ""
			(at 0 0 0)
			(layer "F.Fab")
			(effects
				(font
					(size 1.27 1.27)
				)
			)
		)
		(duplicate_pad_numbers_are_jumpers no)
		(fp_line
			(start -1.332738 -1.100074)
			(end -0.4826 -1.100074)
			(stroke
				(width 0.1524)
				(type default)
			)
			(layer "F.SilkS")
		)
		(fp_line
			(start -1.332738 1.100074)
			(end -1.332738 -1.100074)
			(stroke
				(width 0.1524)
				(type default)
			)
			(layer "F.SilkS")
		)
		(fp_line
			(start -0.4826 -1.100074)
			(end 0 -0.541274)
			(stroke
				(width 0.1524)
				(type default)
			)
			(layer "F.SilkS")
		)
		(fp_line
			(start 0 -0.541274)
			(end 0.4826 -1.100074)
			(stroke
				(width 0.1524)
				(type default)
			)
			(layer "F.SilkS")
		)
		(fp_line
			(start 0.4826 -1.100074)
			(end 1.332738 -1.100074)
			(stroke
				(width 0.1524)
				(type default)
			)
			(layer "F.SilkS")
		)
		(fp_line
			(start 1.332738 -1.100074)
			(end 1.332738 1.100074)
			(stroke
				(width 0.1524)
				(type default)
			)
			(layer "F.SilkS")
		)
		(fp_line
			(start 1.332738 1.100074)
			(end -1.332738 1.100074)
			(stroke
				(width 0.1524)
				(type default)
			)
			(layer "F.SilkS")
		)
		(fp_poly
			(pts
				(xy -1.921764 -1.517396) (xy -1.425194 -2.013966) (xy -1.177036 -1.269238)
			)
			(stroke
				(width 0)
				(type default)
			)
			(fill yes)
			(layer "F.SilkS")
		)
		(fp_line
			(start -0.674878 -1.100074)
			(end 0.674878 -1.100074)
			(stroke
				(width 0.1)
				(type default)
			)
			(layer "F.Fab")
		)
		(fp_line
			(start -0.674878 1.100074)
			(end -0.674878 -1.100074)
			(stroke
				(width 0.1)
				(type default)
			)
			(layer "F.Fab")
		)
		(fp_line
			(start 0.674878 -1.100074)
			(end 0.674878 1.100074)
			(stroke
				(width 0.1)
				(type default)
			)
			(layer "F.Fab")
		)
		(fp_line
			(start 0.674878 1.100074)
			(end -0.674878 1.100074)
			(stroke
				(width 0.1)
				(type default)
			)
			(layer "F.Fab")
		)
		(fp_poly
			(pts
				(xy -2.2352 -0.298958) (xy -2.2352 -1.001014) (xy -1.533144 -0.649986)
			)
			(stroke
				(width 0)
				(type default)
			)
			(fill yes)
			(layer "F.Fab")
		)
		(pad "1" smd rect
			(at -0.94996 -0.649986 90)
			(size 0.4318 0.508)
			(layers "F.Cu" "F.Mask" "F.Paste")
			(net "GND")
		)
		(pad "2" smd rect
			(at -0.94996 0 90)
			(size 0.4318 0.508)
			(layers "F.Cu" "F.Mask" "F.Paste")
			(net "PRSNT_CABLE_SWB_B2_N")
		)
		(pad "3" smd rect
			(at -0.94996 0.649986 90)
			(size 0.4318 0.508)
			(layers "F.Cu" "F.Mask" "F.Paste")
			(net "PRSNT_CABLE_SWB_B2_ISO_N")
		)
		(pad "4" smd rect
			(at 0.94996 0.649986 90)
			(size 0.4318 0.508)
			(layers "F.Cu" "F.Mask" "F.Paste")
			(net "GND")
		)
		(pad "5" smd rect
			(at 0.94996 0 90)
			(size 0.4318 0.508)
			(layers "F.Cu" "F.Mask" "F.Paste")
			(net "PRSNT_CABLE_SWB_B2")
		)
		(pad "6" smd rect
			(at 0.94996 -0.649986 90)
			(size 0.4318 0.508)
			(layers "F.Cu" "F.Mask" "F.Paste")
			(net "PRSNT_CABLE_SWB_B2")
		)
	)
	(footprint ""
		(layer "F.Cu")
		(at 435.431692 -181.13121 90)
		(property "Reference" "PC1275"
			(at 0 0 90)
			(layer "F.SilkS")
			(hide yes)
			(effects
				(font
					(size 1.27 1.27)
				)
			)
		)
		(property "Value" ""
			(at 0 0 90)
			(layer "F.Fab")
			(effects
				(font
					(size 1.27 1.27)
				)
			)
		)
		(duplicate_pad_numbers_are_jumpers no)
		(fp_line
			(start 0.7874 -0.4064)
			(end 0.7874 0.4064)
			(stroke
				(width 0.1524)
				(type default)
			)
			(layer "F.SilkS")
		)
		(fp_line
			(start -0.7874 -0.4064)
			(end 0.7874 -0.4064)
			(stroke
				(width 0.1524)
				(type default)
			)
			(layer "F.SilkS")
		)
		(fp_line
			(start 0.7874 0.4064)
			(end -0.7874 0.4064)
			(stroke
				(width 0.1524)
				(type default)
			)
			(layer "F.SilkS")
		)
		(fp_line
			(start -0.7874 0.4064)
			(end -0.7874 -0.4064)
			(stroke
				(width 0.1524)
				(type default)
			)
			(layer "F.SilkS")
		)
		(fp_line
			(start -0.12065 -0.305054)
			(end -0.12065 -0.2794)
			(stroke
				(width 0.1)
				(type default)
			)
			(layer "F.Fab")
		)
		(fp_line
			(start -0.67945 -0.305054)
			(end -0.12065 -0.305054)
			(stroke
				(width 0.1)
				(type default)
			)
			(layer "F.Fab")
		)
		(fp_line
			(start 0.67945 -0.3048)
			(end 0.67945 0.3048)
			(stroke
				(width 0.1)
				(type default)
			)
			(layer "F.Fab")
		)
		(fp_line
			(start 0.12065 -0.3048)
			(end 0.67945 -0.3048)
			(stroke
				(width 0.1)
				(type default)
			)
			(layer "F.Fab")
		)
		(fp_line
			(start 0.12065 -0.2794)
			(end 0.12065 -0.3048)
			(stroke
				(width 0.1)
				(type default)
			)
			(layer "F.Fab")
		)
		(fp_line
			(start -0.12065 -0.2794)
			(end 0.12065 -0.2794)
			(stroke
				(width 0.1)
				(type default)
			)
			(layer "F.Fab")
		)
		(fp_line
			(start 0.120396 0.2794)
			(end -0.12065 0.2794)
			(stroke
				(width 0.1)
				(type default)
			)
			(layer "F.Fab")
		)
		(fp_line
			(start -0.12065 0.2794)
			(end -0.12065 0.3048)
			(stroke
				(width 0.1)
				(type default)
			)
			(layer "F.Fab")
		)
		(fp_line
			(start 0.67945 0.3048)
			(end 0.120396 0.3048)
			(stroke
				(width 0.1)
				(type default)
			)
			(layer "F.Fab")
		)
		(fp_line
			(start 0.120396 0.3048)
			(end 0.120396 0.2794)
			(stroke
				(width 0.1)
				(type default)
			)
			(layer "F.Fab")
		)
		(fp_line
			(start -0.12065 0.3048)
			(end -0.67945 0.3048)
			(stroke
				(width 0.1)
				(type default)
			)
			(layer "F.Fab")
		)
		(fp_line
			(start -0.67945 0.3048)
			(end -0.67945 -0.305054)
			(stroke
				(width 0.1)
				(type default)
			)
			(layer "F.Fab")
		)
		(pad "1" smd circle
			(at -0.40005 0 90)
			(size 0 0)
			(layers "F.Cu" "F.Mask" "F.Paste")
			(net "SW_PVNN_MAIN_CPU0_BST_R")
		)
		(pad "2" smd circle
			(at 0.40005 0 90)
			(size 0 0)
			(layers "F.Cu" "F.Mask" "F.Paste")
			(net "SW_PVNN_MAIN_CPU0_SW")
		)
	)
)
